FILE_TYPE = MULTI_PHYS_TABLE;
PART 'PCA9517'
{========================================================================================================================================================}
:PACK_TYPE|MATERIAL|PART_NUMBER= EnvComp |PART_NUMBER|JEDEC_TYPE|DESCRIPTION|CLASS|COMPONENT_TYPE|HEIGHT| LPID   | SPEED_URL | Status |RPL| AML | Bus_Unit | Days ;
{========================================================================================================================================================}
'SM'       |'IC'      | 'G77073-001'(!) = 'YES;YES;YES;UNK;ok;VLD' | 'G77073-001' |'SSOP8_12_65MC' |'IC,I2C,SMBUS,TSSOP8,LF/HF'   | 'IC'  | 'SUB50'       | '0.043 IN' |'2481'| 'http://speed.intel.com:8081/speed/module/pdm/item/pdm_item_detail_direct.asp?item_cde=G77073-001&item_rev=01&url_param=unused' | 'Design' | 'YES' | '2' | 'SMO_IC' | '???' 
'SM'       |'EMPTY'   | 'G77073-001'(!) = 'YES;YES;YES;UNK;ok;VLD' | 'G77073-001' |'SSOP8_12_65MC' |'IC,I2C,SMBUS,TSSOP8,LF/HF'   | 'IO'  | 'SUB50'       | '0.043 IN' |'2481'| 'http://speed.intel.com:8081/speed/module/pdm/item/pdm_item_detail_direct.asp?item_cde=G77073-001&item_rev=01&url_param=unused' | 'Design' | 'YES' | '2' | 'SMO_IC' | '???' 
END_PART
END.
